(kicad_pcb
	(version 20260206)
	(generator "pcbnew")
	(generator_version "10.0")
	(general
		(thickness 1.6)
		(legacy_teardrops no)
	)
	(paper "A4")
	(title_block
		(title "03242023_DA0F0TMBIJ0_F0T_Motherboard_J_brd_V01_OCP.brd")
		(comment 1 "Grand Teton / footprints 3090-3095 of 6105")
	)
	(layers
		(0 "F.Cu" signal "TOP")
		(4 "In1.Cu" signal "GND")
		(6 "In2.Cu" signal "IN1")
		(8 "In3.Cu" signal "GND1")
		(10 "In4.Cu" signal "IN2")
		(12 "In5.Cu" signal "GND2")
		(14 "In6.Cu" signal "IN3")
		(16 "In7.Cu" signal "GND3")
		(18 "In8.Cu" signal "VCC")
		(20 "In9.Cu" signal "VCC1")
		(22 "In10.Cu" signal "GND4")
		(24 "In11.Cu" signal "IN4")
		(26 "In12.Cu" signal "GND5")
		(28 "In13.Cu" signal "IN5")
		(30 "In14.Cu" signal "GND6")
		(32 "In15.Cu" signal "IN6")
		(34 "In16.Cu" signal "GND7")
		(2 "B.Cu" signal "BOTTOM")
		(9 "F.Adhes" user "F.Adhesive")
		(11 "B.Adhes" user "B.Adhesive")
		(13 "F.Paste" user "Package Geometry/Pastemask Top")
		(15 "B.Paste" user "Package Geometry/Pastemask Bottom")
		(5 "F.SilkS" user "Ref Des/Silkscreen Top")
		(7 "B.SilkS" user "Ref Des/Silkscreen Bottom")
		(1 "F.Mask" user "Board Geometry/Soldermask Top")
		(3 "B.Mask" user "Board Geometry/Soldermask Bottom")
		(17 "Dwgs.User" user "User.Drawings")
		(19 "Cmts.User" user "User.Comments")
		(21 "Eco1.User" user "User.Eco1")
		(23 "Eco2.User" user "User.Eco2")
		(25 "Edge.Cuts" user "Board Geometry/Outline")
		(27 "Margin" user)
		(31 "F.CrtYd" user "Package Geometry/Place Bound Top")
		(29 "B.CrtYd" user "Package Geometry/Place Bound Bottom")
		(35 "F.Fab" user "Ref Des/Assembly Top")
		(33 "B.Fab" user "Ref Des/Assembly Bottom")
	)
	(footprint ""
		(layer "F.Cu")
		(at 385.637532 -72.378824)
		(property "Reference" "R2360"
			(at 0 0 0)
			(layer "F.SilkS")
			(hide yes)
			(effects
				(font
					(size 1.27 1.27)
				)
			)
		)
		(property "Value" ""
			(at 0 0 0)
			(layer "F.Fab")
			(effects
				(font
					(size 1.27 1.27)
				)
			)
		)
		(duplicate_pad_numbers_are_jumpers no)
		(fp_line
			(start -0.7874 -0.4064)
			(end 0.7874 -0.4064)
			(stroke
				(width 0.1524)
				(type default)
			)
			(layer "F.SilkS")
		)
		(fp_line
			(start -0.7874 0.4064)
			(end -0.7874 -0.4064)
			(stroke
				(width 0.1524)
				(type default)
			)
			(layer "F.SilkS")
		)
		(fp_line
			(start 0.7874 -0.4064)
			(end 0.7874 0.4064)
			(stroke
				(width 0.1524)
				(type default)
			)
			(layer "F.SilkS")
		)
		(fp_line
			(start 0.7874 0.4064)
			(end -0.7874 0.4064)
			(stroke
				(width 0.1524)
				(type default)
			)
			(layer "F.SilkS")
		)
		(fp_line
			(start -0.67945 -0.305054)
			(end -0.12065 -0.305054)
			(stroke
				(width 0.1)
				(type default)
			)
			(layer "F.Fab")
		)
		(fp_line
			(start -0.67945 0.3048)
			(end -0.67945 -0.305054)
			(stroke
				(width 0.1)
				(type default)
			)
			(layer "F.Fab")
		)
		(fp_line
			(start -0.12065 -0.305054)
			(end -0.12065 -0.2794)
			(stroke
				(width 0.1)
				(type default)
			)
			(layer "F.Fab")
		)
		(fp_line
			(start -0.12065 -0.2794)
			(end 0.12065 -0.2794)
			(stroke
				(width 0.1)
				(type default)
			)
			(layer "F.Fab")
		)
		(fp_line
			(start -0.12065 0.2794)
			(end -0.12065 0.3048)
			(stroke
				(width 0.1)
				(type default)
			)
			(layer "F.Fab")
		)
		(fp_line
			(start -0.12065 0.3048)
			(end -0.67945 0.3048)
			(stroke
				(width 0.1)
				(type default)
			)
			(layer "F.Fab")
		)
		(fp_line
			(start 0.120396 0.2794)
			(end -0.12065 0.2794)
			(stroke
				(width 0.1)
				(type default)
			)
			(layer "F.Fab")
		)
		(fp_line
			(start 0.120396 0.3048)
			(end 0.120396 0.2794)
			(stroke
				(width 0.1)
				(type default)
			)
			(layer "F.Fab")
		)
		(fp_line
			(start 0.12065 -0.3048)
			(end 0.67945 -0.3048)
			(stroke
				(width 0.1)
				(type default)
			)
			(layer "F.Fab")
		)
		(fp_line
			(start 0.12065 -0.2794)
			(end 0.12065 -0.3048)
			(stroke
				(width 0.1)
				(type default)
			)
			(layer "F.Fab")
		)
		(fp_line
			(start 0.67945 -0.3048)
			(end 0.67945 0.3048)
			(stroke
				(width 0.1)
				(type default)
			)
			(layer "F.Fab")
		)
		(fp_line
			(start 0.67945 0.3048)
			(end 0.120396 0.3048)
			(stroke
				(width 0.1)
				(type default)
			)
			(layer "F.Fab")
		)
		(pad "1" smd circle
			(at -0.40005 0)
			(size 0 0)
			(layers "F.Cu" "F.Mask" "F.Paste")
			(net "PWRGD_P1V8_PCH_AUX_R")
		)
		(pad "2" smd circle
			(at 0.40005 0)
			(size 0 0)
			(layers "F.Cu" "F.Mask" "F.Paste")
			(net "PWRGD_P1V8_PCH_AUX")
		)
	)
	(footprint ""
		(layer "F.Cu")
		(at 353.245928 -258.726686 90)
		(property "Reference" "C419"
			(at 0 0 90)
			(layer "F.SilkS")
			(hide yes)
			(effects
				(font
					(size 1.27 1.27)
				)
			)
		)
		(property "Value" ""
			(at 0 0 90)
			(layer "F.Fab")
			(effects
				(font
					(size 1.27 1.27)
				)
			)
		)
		(duplicate_pad_numbers_are_jumpers no)
		(fp_line
			(start 0.7874 -0.4064)
			(end 0.7874 0.4064)
			(stroke
				(width 0.1524)
				(type default)
			)
			(layer "F.SilkS")
		)
		(fp_line
			(start -0.7874 -0.4064)
			(end 0.7874 -0.4064)
			(stroke
				(width 0.1524)
				(type default)
			)
			(layer "F.SilkS")
		)
		(fp_line
			(start 0.7874 0.4064)
			(end -0.7874 0.4064)
			(stroke
				(width 0.1524)
				(type default)
			)
			(layer "F.SilkS")
		)
		(fp_line
			(start -0.7874 0.4064)
			(end -0.7874 -0.4064)
			(stroke
				(width 0.1524)
				(type default)
			)
			(layer "F.SilkS")
		)
		(fp_line
			(start -0.12065 -0.305054)
			(end -0.12065 -0.2794)
			(stroke
				(width 0.1)
				(type default)
			)
			(layer "F.Fab")
		)
		(fp_line
			(start -0.67945 -0.305054)
			(end -0.12065 -0.305054)
			(stroke
				(width 0.1)
				(type default)
			)
			(layer "F.Fab")
		)
		(fp_line
			(start 0.67945 -0.3048)
			(end 0.67945 0.3048)
			(stroke
				(width 0.1)
				(type default)
			)
			(layer "F.Fab")
		)
		(fp_line
			(start 0.12065 -0.3048)
			(end 0.67945 -0.3048)
			(stroke
				(width 0.1)
				(type default)
			)
			(layer "F.Fab")
		)
		(fp_line
			(start 0.12065 -0.2794)
			(end 0.12065 -0.3048)
			(stroke
				(width 0.1)
				(type default)
			)
			(layer "F.Fab")
		)
		(fp_line
			(start -0.12065 -0.2794)
			(end 0.12065 -0.2794)
			(stroke
				(width 0.1)
				(type default)
			)
			(layer "F.Fab")
		)
		(fp_line
			(start 0.120396 0.2794)
			(end -0.12065 0.2794)
			(stroke
				(width 0.1)
				(type default)
			)
			(layer "F.Fab")
		)
		(fp_line
			(start -0.12065 0.2794)
			(end -0.12065 0.3048)
			(stroke
				(width 0.1)
				(type default)
			)
			(layer "F.Fab")
		)
		(fp_line
			(start 0.67945 0.3048)
			(end 0.120396 0.3048)
			(stroke
				(width 0.1)
				(type default)
			)
			(layer "F.Fab")
		)
		(fp_line
			(start 0.120396 0.3048)
			(end 0.120396 0.2794)
			(stroke
				(width 0.1)
				(type default)
			)
			(layer "F.Fab")
		)
		(fp_line
			(start -0.12065 0.3048)
			(end -0.67945 0.3048)
			(stroke
				(width 0.1)
				(type default)
			)
			(layer "F.Fab")
		)
		(fp_line
			(start -0.67945 0.3048)
			(end -0.67945 -0.305054)
			(stroke
				(width 0.1)
				(type default)
			)
			(layer "F.Fab")
		)
		(pad "1" smd circle
			(at -0.40005 0 90)
			(size 0 0)
			(layers "F.Cu" "F.Mask" "F.Paste")
			(net "PVCCFA_EHV_CPU0")
		)
		(pad "2" smd circle
			(at 0.40005 0 90)
			(size 0 0)
			(layers "F.Cu" "F.Mask" "F.Paste")
			(net "GND")
		)
	)
	(footprint ""
		(layer "F.Cu")
		(at 321.899788 -26.711656 90)
		(property "Reference" "R1694"
			(at 0 0 90)
			(layer "F.SilkS")
			(hide yes)
			(effects
				(font
					(size 1.27 1.27)
				)
			)
		)
		(property "Value" ""
			(at 0 0 90)
			(layer "F.Fab")
			(effects
				(font
					(size 1.27 1.27)
				)
			)
		)
		(duplicate_pad_numbers_are_jumpers no)
		(fp_line
			(start 0.7874 -0.4064)
			(end 0.7874 0.4064)
			(stroke
				(width 0.1524)
				(type default)
			)
			(layer "F.SilkS")
		)
		(fp_line
			(start -0.7874 -0.4064)
			(end 0.7874 -0.4064)
			(stroke
				(width 0.1524)
				(type default)
			)
			(layer "F.SilkS")
		)
		(fp_line
			(start 0.7874 0.4064)
			(end -0.7874 0.4064)
			(stroke
				(width 0.1524)
				(type default)
			)
			(layer "F.SilkS")
		)
		(fp_line
			(start -0.7874 0.4064)
			(end -0.7874 -0.4064)
			(stroke
				(width 0.1524)
				(type default)
			)
			(layer "F.SilkS")
		)
		(fp_line
			(start -0.12065 -0.305054)
			(end -0.12065 -0.2794)
			(stroke
				(width 0.1)
				(type default)
			)
			(layer "F.Fab")
		)
		(fp_line
			(start -0.67945 -0.305054)
			(end -0.12065 -0.305054)
			(stroke
				(width 0.1)
				(type default)
			)
			(layer "F.Fab")
		)
		(fp_line
			(start 0.67945 -0.3048)
			(end 0.67945 0.3048)
			(stroke
				(width 0.1)
				(type default)
			)
			(layer "F.Fab")
		)
		(fp_line
			(start 0.12065 -0.3048)
			(end 0.67945 -0.3048)
			(stroke
				(width 0.1)
				(type default)
			)
			(layer "F.Fab")
		)
		(fp_line
			(start 0.12065 -0.2794)
			(end 0.12065 -0.3048)
			(stroke
				(width 0.1)
				(type default)
			)
			(layer "F.Fab")
		)
		(fp_line
			(start -0.12065 -0.2794)
			(end 0.12065 -0.2794)
			(stroke
				(width 0.1)
				(type default)
			)
			(layer "F.Fab")
		)
		(fp_line
			(start 0.120396 0.2794)
			(end -0.12065 0.2794)
			(stroke
				(width 0.1)
				(type default)
			)
			(layer "F.Fab")
		)
		(fp_line
			(start -0.12065 0.2794)
			(end -0.12065 0.3048)
			(stroke
				(width 0.1)
				(type default)
			)
			(layer "F.Fab")
		)
		(fp_line
			(start 0.67945 0.3048)
			(end 0.120396 0.3048)
			(stroke
				(width 0.1)
				(type default)
			)
			(layer "F.Fab")
		)
		(fp_line
			(start 0.120396 0.3048)
			(end 0.120396 0.2794)
			(stroke
				(width 0.1)
				(type default)
			)
			(layer "F.Fab")
		)
		(fp_line
			(start -0.12065 0.3048)
			(end -0.67945 0.3048)
			(stroke
				(width 0.1)
				(type default)
			)
			(layer "F.Fab")
		)
		(fp_line
			(start -0.67945 0.3048)
			(end -0.67945 -0.305054)
			(stroke
				(width 0.1)
				(type default)
			)
			(layer "F.Fab")
		)
		(pad "1" smd circle
			(at -0.40005 0 90)
			(size 0 0)
			(layers "F.Cu" "F.Mask" "F.Paste")
			(net "P3V3_AUX")
		)
		(pad "2" smd circle
			(at 0.40005 0 90)
			(size 0 0)
			(layers "F.Cu" "F.Mask" "F.Paste")
			(net "PWRGD_DSW_PWROK")
		)
	)
	(footprint ""
		(layer "F.Cu")
		(at 389.77697 -402.371052 -90)
		(property "Reference" "C947"
			(at 0 0 270)
			(layer "F.SilkS")
			(hide yes)
			(effects
				(font
					(size 1.27 1.27)
				)
			)
		)
		(property "Value" ""
			(at 0 0 270)
			(layer "F.Fab")
			(effects
				(font
					(size 1.27 1.27)
				)
			)
		)
		(duplicate_pad_numbers_are_jumpers no)
		(fp_line
			(start -0.299974 0.150114)
			(end -0.299974 -0.150114)
			(stroke
				(width 0.1)
				(type default)
			)
			(layer "F.Fab")
		)
		(fp_line
			(start 0.299974 0.150114)
			(end -0.299974 0.150114)
			(stroke
				(width 0.1)
				(type default)
			)
			(layer "F.Fab")
		)
		(fp_line
			(start -0.299974 -0.150114)
			(end 0.299974 -0.150114)
			(stroke
				(width 0.1)
				(type default)
			)
			(layer "F.Fab")
		)
		(fp_line
			(start 0.299974 -0.150114)
			(end 0.299974 0.150114)
			(stroke
				(width 0.1)
				(type default)
			)
			(layer "F.Fab")
		)
		(pad "1" smd rect
			(at -0.2667 0 270)
			(size 0.3048 0.381)
			(layers "F.Cu" "F.Mask" "F.Paste")
			(net "P5E_CPU0_PE2_TX_C_DP<9>")
		)
		(pad "2" smd rect
			(at 0.2667 0 270)
			(size 0.3048 0.381)
			(layers "F.Cu" "F.Mask" "F.Paste")
			(net "P5E_CPU0_PE2_TX_DP<9>")
		)
	)
	(footprint ""
		(layer "F.Cu")
		(at 479.84537 -184.606692 -90)
		(property "Reference" "X43"
			(at 2.361692 4.7117 90)
			(unlocked yes)
			(layer "F.SilkS")
			(effects
				(font
					(size 0.7874 0.5842)
					(thickness 0.1524)
				)
				(justify left)
			)
		)
		(property "Value" ""
			(at 0 0 270)
			(layer "F.Fab")
			(effects
				(font
					(size 1.27 1.27)
				)
			)
		)
		(property "Device Type" "TP_TDR_4P_FTS_TH-TP_TDR_4P_DIPA"
			(at 1.30175 1.27 0)
			(unlocked yes)
			(layer "F.Fab")
			(hide yes)
			(effects
				(font
					(size 0.635 0.4064)
					(thickness 0.1524)
				)
			)
		)
		(property "User Part Number" "N_A"
			(at 1.30175 1.27 0)
			(unlocked yes)
			(layer "Cmts.User")
			(hide yes)
			(effects
				(font
					(size 0.635 0.4064)
					(thickness 0.1524)
				)
			)
		)
		(duplicate_pad_numbers_are_jumpers no)
		(fp_line
			(start 0 3.81)
			(end 2.54 3.81)
			(stroke
				(width 0.1524)
				(type default)
			)
			(layer "F.SilkS")
		)
		(fp_line
			(start 2.54 3.81)
			(end 2.54 3.6703)
			(stroke
				(width 0.1524)
				(type default)
			)
			(layer "F.SilkS")
		)
		(fp_line
			(start 0 3.175)
			(end 0 3.81)
			(stroke
				(width 0.1524)
				(type default)
			)
			(layer "F.SilkS")
		)
		(fp_line
			(start 2.54 1.4097)
			(end 2.54 1.1303)
			(stroke
				(width 0.1524)
				(type default)
			)
			(layer "F.SilkS")
		)
		(fp_line
			(start 0 0.635)
			(end 0 1.905)
			(stroke
				(width 0.1524)
				(type default)
			)
			(layer "F.SilkS")
		)
		(fp_line
			(start 2.54 -1.1303)
			(end 2.54 -1.27)
			(stroke
				(width 0.1524)
				(type default)
			)
			(layer "F.SilkS")
		)
		(fp_line
			(start 0 -1.27)
			(end 0 -0.635)
			(stroke
				(width 0.1524)
				(type default)
			)
			(layer "F.SilkS")
		)
		(fp_line
			(start 2.54 -1.27)
			(end 0 -1.27)
			(stroke
				(width 0.1524)
				(type default)
			)
			(layer "F.SilkS")
		)
		(fp_poly
			(pts
				(xy -0.761746 0) (xy -2.285746 -0.762) (xy -2.285746 0.762)
			)
			(stroke
				(width 0)
				(type default)
			)
			(fill yes)
			(layer "F.SilkS")
		)
		(fp_line
			(start 0 3.81)
			(end 2.54 3.81)
			(stroke
				(width 0.1)
				(type default)
			)
			(layer "F.Fab")
		)
		(fp_line
			(start 2.54 3.81)
			(end 2.54 -1.27)
			(stroke
				(width 0.1)
				(type default)
			)
			(layer "F.Fab")
		)
		(fp_line
			(start 0 -1.27)
			(end 0 3.81)
			(stroke
				(width 0.1)
				(type default)
			)
			(layer "F.Fab")
		)
		(fp_line
			(start 2.54 -1.27)
			(end 0 -1.27)
			(stroke
				(width 0.1)
				(type default)
			)
			(layer "F.Fab")
		)
		(fp_poly
			(pts
				(xy -0.761746 0) (xy -2.285746 -0.762) (xy -2.285746 0.762)
			)
			(stroke
				(width 0)
				(type default)
			)
			(fill yes)
			(layer "F.Fab")
		)
		(pad "1" thru_hole circle
			(at 0 0 270)
			(size 1.0033 1.0033)
			(drill 0.249936)
			(layers "*.Cu" "*.Mask")
			(remove_unused_layers no)
			(net "TDR_DIFF_85_NECK_IN2_DN")
			(clearance 0.10795)
			(thermal_gap 0.10795)
			(padstack
				(mode front_inner_back)
				(layer "Inner"
					(shape circle)
					(size 0.8001 0.8001)
					(clearance 0.1524)
				)
				(layer "B.Cu"
					(shape circle)
					(size 1.0033 1.0033)
					(clearance 0.10795)
				)
			)
		)
		(pad "2" thru_hole circle
			(at 2.54 0 270)
			(size 1.9939 1.9939)
			(drill 0.249936)
			(layers "*.Cu" "*.Mask")
			(remove_unused_layers no)
			(net "T1_GND")
			(clearance 0.10795)
			(thermal_gap 0.10795)
			(padstack
				(mode front_inner_back)
				(layer "Inner"
					(shape circle)
					(size 0.8001 0.8001)
					(clearance 0.1524)
				)
				(layer "B.Cu"
					(shape circle)
					(size 1.9939 1.9939)
					(clearance 0.10795)
				)
			)
		)
		(pad "3" thru_hole circle
			(at 2.54 2.54 270)
			(size 1.9939 1.9939)
			(drill 0.249936)
			(layers "*.Cu" "*.Mask")
			(remove_unused_layers no)
			(net "T1_GND")
			(clearance 0.10795)
			(thermal_gap 0.10795)
			(padstack
				(mode front_inner_back)
				(layer "Inner"
					(shape circle)
					(size 0.8001 0.8001)
					(clearance 0.1524)
				)
				(layer "B.Cu"
					(shape circle)
					(size 1.9939 1.9939)
					(clearance 0.10795)
				)
			)
		)
		(pad "4" thru_hole circle
			(at 0 2.54 270)
			(size 1.0033 1.0033)
			(drill 0.249936)
			(layers "*.Cu" "*.Mask")
			(remove_unused_layers no)
			(net "TDR_DIFF_85_NECK_IN2_DP")
			(clearance 0.10795)
			(thermal_gap 0.10795)
			(padstack
				(mode front_inner_back)
				(layer "Inner"
					(shape circle)
					(size 0.8001 0.8001)
					(clearance 0.1524)
				)
				(layer "B.Cu"
					(shape circle)
					(size 1.0033 1.0033)
					(clearance 0.10795)
				)
			)
		)
	)
	(footprint ""
		(layer "F.Cu")
		(at 183.353964 -337.483958)
		(property "Reference" "PC1201"
			(at 0 0 0)
			(layer "F.SilkS")
			(hide yes)
			(effects
				(font
					(size 1.27 1.27)
				)
			)
		)
		(property "Value" ""
			(at 0 0 0)
			(layer "F.Fab")
			(effects
				(font
					(size 1.27 1.27)
				)
			)
		)
		(duplicate_pad_numbers_are_jumpers no)
		(fp_line
			(start 2.750058 0.999998)
			(end -2.750058 0.999998)
			(stroke
				(width 0.1524)
				(type default)
			)
			(layer "F.SilkS")
		)
		(fp_circle
			(center 0 0.999998)
			(end 2.750058 0.999998)
			(stroke
				(width 0.1524)
				(type default)
			)
			(fill no)
			(layer "F.SilkS")
		)
		(fp_poly
			(pts
				(arc
					(start 2.750058 0.999998)
					(mid 0 3.750056)
					(end -2.750058 0.999998)
				)
			)
			(stroke
				(width 0)
				(type default)
			)
			(fill yes)
			(layer "F.SilkS")
		)
		(fp_circle
			(center 0 0.999998)
			(end 2.750058 0.999998)
			(stroke
				(width 0.1)
				(type default)
			)
			(fill no)
			(layer "F.Fab")
		)
		(pad "1" thru_hole rect
			(at 0 0)
			(size 1.5748 1.5748)
			(drill 1.0668)
			(layers "*.Cu" "*.Mask")
			(remove_unused_layers no)
			(net "PVCCFA_EHV_FIVRA_CPU1")
			(clearance 0)
			(padstack
				(mode front_inner_back)
				(layer "Inner"
					(shape circle)
					(size 1.5748 1.5748)
					(clearance 0)
				)
				(layer "B.Cu"
					(shape rect)
					(size 1.5748 1.5748)
					(clearance 0)
				)
			)
		)
		(pad "2" thru_hole circle
			(at 0 1.999996)
			(size 1.5748 1.5748)
			(drill 1.0668)
			(layers "*.Cu" "*.Mask")
			(remove_unused_layers no)
			(net "GND")
			(clearance 0)
		)
	)
)
